(kicad_pcb
	(version 20240108)
	(generator "pcbnew")
	(generator_version "8.0")
	(general
		(thickness 1.62)
		(legacy_teardrops no)
	)
	(paper "A4")
	(title_block
		(title "Jetson Orin Baseboard")
		(date "2025-03-12")
		(rev "1.3.4")
		(company "Antmicro Ltd")
		(comment 1 "www.antmicro.com")
		(comment 9 "footprints 556-559 of 677")
	)
	(layers
		(0 "F.Cu" signal)
		(1 "In1.Cu" signal)
		(2 "In2.Cu" signal)
		(3 "In3.Cu" signal)
		(4 "In4.Cu" jumper)
		(5 "In5.Cu" signal)
		(6 "In6.Cu" signal)
		(31 "B.Cu" signal)
		(32 "B.Adhes" user "B.Adhesive")
		(33 "F.Adhes" user "F.Adhesive")
		(34 "B.Paste" user)
		(35 "F.Paste" user)
		(36 "B.SilkS" user "B.Silkscreen")
		(37 "F.SilkS" user "F.Silkscreen")
		(38 "B.Mask" user)
		(39 "F.Mask" user)
		(40 "Dwgs.User" user "User.Drawings")
		(41 "Cmts.User" user "User.Comments")
		(42 "Eco1.User" user "User.Eco1")
		(43 "Eco2.User" user "User.Eco2")
		(44 "Edge.Cuts" user)
		(45 "Margin" user)
		(46 "B.CrtYd" user "B.Courtyard")
		(47 "F.CrtYd" user "F.Courtyard")
		(48 "B.Fab" user)
		(49 "F.Fab" user)
	)
	(footprint "antmicro-footprints:LED_0603_1608Metric_G"
		(layer "B.Cu")
		(at 144.5 112.5 180)
		(descr "LED SMD 0603 Green")
		(tags "LED SMD 0603 Green")
		(property "Reference" "D20"
			(at -1.05 0.6 180)
			(layer "B.SilkS")
			(effects
				(font
					(size 0.7 0.7)
					(thickness 0.15)
				)
				(justify left bottom mirror)
			)
		)
		(property "Value" "LED_G_0603_LTST-C190GKT"
			(at -0.001 -1.599 0)
			(layer "B.Fab")
			(effects
				(font
					(size 0.7 0.7)
					(thickness 0.15)
				)
				(justify left bottom mirror)
			)
		)
		(property "Footprint" "antmicro-footprints:LED_0603_1608Metric_G"
			(at 0 0 180)
			(layer "F.Fab")
			(hide yes)
			(effects
				(font
					(size 1.27 1.27)
					(thickness 0.15)
				)
			)
		)
		(property "Datasheet" "https://media.digikey.com/pdf/Data%20Sheets/Lite-On%20PDFs/LTST-C190GKT.pdf"
			(at 0 0 180)
			(layer "F.Fab")
			(hide yes)
			(effects
				(font
					(size 1.27 1.27)
					(thickness 0.15)
				)
			)
		)
		(property "Author" "Antmicro"
			(at 289 225 0)
			(layer "B.Fab")
			(hide yes)
			(effects
				(font
					(size 1 1)
					(thickness 0.15)
				)
				(justify mirror)
			)
		)
		(property "Color" "Green"
			(at 289 225 0)
			(layer "B.Fab")
			(hide yes)
			(effects
				(font
					(size 1 1)
					(thickness 0.15)
				)
				(justify mirror)
			)
		)
		(property "License" "Apache-2.0"
			(at 289 225 0)
			(layer "B.Fab")
			(hide yes)
			(effects
				(font
					(size 1 1)
					(thickness 0.15)
				)
				(justify mirror)
			)
		)
		(property "MPN" "LTST-C190GKT"
			(at 289 225 0)
			(layer "B.Fab")
			(hide yes)
			(effects
				(font
					(size 1 1)
					(thickness 0.15)
				)
				(justify mirror)
			)
		)
		(property "Manufacturer" "Lite-On"
			(at 289 225 0)
			(layer "B.Fab")
			(hide yes)
			(effects
				(font
					(size 1 1)
					(thickness 0.15)
				)
				(justify mirror)
			)
		)
		(sheetname "CSI")
		(sheetfile "csi.kicad_sch")
		(attr smd)
		(fp_line
			(start 0.24 -0.001)
			(end 0.105328 -0.001008)
			(stroke
				(width 0.1)
				(type solid)
			)
			(layer "B.SilkS")
		)
		(fp_line
			(start 0.105328 0.198992)
			(end 0.105328 -0.201008)
			(stroke
				(width 0.1)
				(type solid)
			)
			(layer "B.SilkS")
		)
		(fp_line
			(start 0.105328 0.198992)
			(end -0.094672 -0.001008)
			(stroke
				(width 0.1)
				(type solid)
			)
			(layer "B.SilkS")
		)
		(fp_line
			(start -0.094672 0.198992)
			(end -0.094672 -0.201008)
			(stroke
				(width 0.1)
				(type solid)
			)
			(layer "B.SilkS")
		)
		(fp_line
			(start -0.094672 -0.001008)
			(end 0.105328 -0.201008)
			(stroke
				(width 0.1)
				(type solid)
			)
			(layer "B.SilkS")
		)
		(fp_line
			(start -0.22 0.35)
			(end 0.22 0.35)
			(stroke
				(width 0.15)
				(type solid)
			)
			(layer "B.SilkS")
		)
		(fp_line
			(start -0.22 -0.35)
			(end 0.22 -0.35)
			(stroke
				(width 0.15)
				(type solid)
			)
			(layer "B.SilkS")
		)
		(fp_line
			(start -0.24 -0.001008)
			(end -0.094672 -0.001008)
			(stroke
				(width 0.1)
				(type solid)
			)
			(layer "B.SilkS")
		)
		(fp_line
			(start -1.18 -0.321)
			(end -1.18 0.319)
			(stroke
				(width 0.15)
				(type solid)
			)
			(layer "B.SilkS")
		)
		(fp_rect
			(start 1.25 -0.65)
			(end -1.25 0.65)
			(stroke
				(width 0.05)
				(type solid)
			)
			(fill none)
			(layer "B.CrtYd")
		)
		(fp_line
			(start 0.201 0.202)
			(end 0.201 0)
			(stroke
				(width 0.15)
				(type solid)
			)
			(layer "B.Fab")
		)
		(fp_line
			(start 0.201 0)
			(end 0.599 0)
			(stroke
				(width 0.15)
				(type solid)
			)
			(layer "B.Fab")
		)
		(fp_line
			(start 0.201 0)
			(end 0.201 -0.2)
			(stroke
				(width 0.15)
				(type solid)
			)
			(layer "B.Fab")
		)
		(fp_line
			(start 0.201 -0.2)
			(end -0.101 0)
			(stroke
				(width 0.15)
				(type solid)
			)
			(layer "B.Fab")
		)
		(fp_line
			(start -0.101 0)
			(end 0.201 0.202)
			(stroke
				(width 0.15)
				(type solid)
			)
			(layer "B.Fab")
		)
		(fp_line
			(start -0.199 -0.1)
			(end -0.199 0.202)
			(stroke
				(width 0.15)
				(type solid)
			)
			(layer "B.Fab")
		)
		(fp_line
			(start -0.199 -0.1)
			(end -0.199 -0.2)
			(stroke
				(width 0.15)
				(type solid)
			)
			(layer "B.Fab")
		)
		(fp_line
			(start -0.597 0)
			(end -0.199 0)
			(stroke
				(width 0.15)
				(type solid)
			)
			(layer "B.Fab")
		)
		(fp_rect
			(start 0.848 -0.4)
			(end -0.85 0.402)
			(stroke
				(width 0.15)
				(type solid)
			)
			(fill none)
			(layer "B.Fab")
		)
		(fp_text user "License: Apache-2.0"
			(at -1.4224 -3.599 0)
			(layer "B.Fab")
			(hide yes)
			(effects
				(font
					(size 0.7 0.7)
					(thickness 0.15)
				)
				(justify left bottom mirror)
			)
		)
		(fp_text user "${REFERENCE}"
			(at -1.4224 -5.999 0)
			(layer "B.Fab")
			(hide yes)
			(effects
				(font
					(size 0.7 0.7)
					(thickness 0.15)
				)
				(justify left bottom mirror)
			)
		)
		(fp_text user "Author: Antmicro"
			(at -1.4224 -4.799 0)
			(layer "B.Fab")
			(hide yes)
			(effects
				(font
					(size 0.7 0.7)
					(thickness 0.15)
				)
				(justify left bottom mirror)
			)
		)
		(pad "1" smd roundrect
			(at -0.7 0)
			(size 0.8 1)
			(layers "B.Cu" "B.Paste" "B.Mask")
			(roundrect_rratio 0.2)
			(net 1 "GND")
			(pinfunction "C")
			(pintype "passive")
		)
		(pad "2" smd roundrect
			(at 0.7 0)
			(size 0.8 1)
			(layers "B.Cu" "B.Paste" "B.Mask")
			(roundrect_rratio 0.2)
			(net 160 "Net-(D20-A)")
			(pinfunction "A")
			(pintype "passive")
		)
	)
	(footprint "antmicro-footprints:C_0402_1005Metric"
		(layer "B.Cu")
		(at 66.075 98.05 -90)
		(descr "Capacitor SMD 0402")
		(tags "capacitor SMD 0402")
		(property "Reference" "C28"
			(at -1.11 -1.495 90)
			(layer "B.SilkS")
			(effects
				(font
					(size 0.7 0.7)
					(thickness 0.15)
				)
				(justify left bottom mirror)
			)
		)
		(property "Value" "C_10u_0402"
			(at -1.022927 -2.155213 90)
			(layer "B.Fab")
			(effects
				(font
					(size 0.7 0.7)
					(thickness 0.15)
				)
				(justify left bottom mirror)
			)
		)
		(property "Footprint" "antmicro-footprints:C_0402_1005Metric"
			(at 0 0 -90)
			(layer "F.Fab")
			(hide yes)
			(effects
				(font
					(size 1.27 1.27)
					(thickness 0.15)
				)
			)
		)
		(property "Datasheet" "https://www.yageo.com/en/Chart/Download/pdf/CC0402MRX5R5BB106"
			(at 0 0 -90)
			(layer "F.Fab")
			(hide yes)
			(effects
				(font
					(size 1.27 1.27)
					(thickness 0.15)
				)
			)
		)
		(property "Author" "Antmicro"
			(at -31.975 164.125 0)
			(layer "B.Fab")
			(hide yes)
			(effects
				(font
					(size 1 1)
					(thickness 0.15)
				)
				(justify mirror)
			)
		)
		(property "Dielectric" ""
			(at -31.975 164.125 0)
			(layer "B.Fab")
			(hide yes)
			(effects
				(font
					(size 1 1)
					(thickness 0.15)
				)
				(justify mirror)
			)
		)
		(property "License" "Apache-2.0"
			(at -31.975 164.125 0)
			(layer "B.Fab")
			(hide yes)
			(effects
				(font
					(size 1 1)
					(thickness 0.15)
				)
				(justify mirror)
			)
		)
		(property "MPN" "CC0402MRX5R5BB106"
			(at -31.975 164.125 0)
			(layer "B.Fab")
			(hide yes)
			(effects
				(font
					(size 1 1)
					(thickness 0.15)
				)
				(justify mirror)
			)
		)
		(property "Manufacturer" "YAGEO"
			(at -31.975 164.125 0)
			(layer "B.Fab")
			(hide yes)
			(effects
				(font
					(size 1 1)
					(thickness 0.15)
				)
				(justify mirror)
			)
		)
		(property "Val" "10u"
			(at -31.975 164.125 0)
			(layer "B.Fab")
			(hide yes)
			(effects
				(font
					(size 1 1)
					(thickness 0.15)
				)
				(justify mirror)
			)
		)
		(property "Voltage" ""
			(at -31.975 164.125 0)
			(layer "B.Fab")
			(hide yes)
			(effects
				(font
					(size 1 1)
					(thickness 0.15)
				)
				(justify mirror)
			)
		)
		(sheetname "USB Debug, DP")
		(sheetfile "usb.kicad_sch")
		(attr smd)
		(fp_rect
			(start -0.925 0.47)
			(end 0.925 -0.47)
			(stroke
				(width 0.05)
				(type default)
			)
			(fill none)
			(layer "B.CrtYd")
		)
		(fp_line
			(start -0.494 0.25)
			(end -0.494 -0.248)
			(stroke
				(width 0.15)
				(type solid)
			)
			(layer "B.Fab")
		)
		(fp_line
			(start 0.504 0.25)
			(end -0.494 0.25)
			(stroke
				(width 0.15)
				(type solid)
			)
			(layer "B.Fab")
		)
		(fp_line
			(start -0.494 -0.248)
			(end 0.504 -0.248)
			(stroke
				(width 0.15)
				(type solid)
			)
			(layer "B.Fab")
		)
		(fp_line
			(start 0.504 -0.248)
			(end 0.504 0.25)
			(stroke
				(width 0.15)
				(type solid)
			)
			(layer "B.Fab")
		)
		(fp_text user "${REFERENCE}"
			(at -0.939 -4.599 90)
			(layer "B.Fab")
			(hide yes)
			(effects
				(font
					(size 0.7 0.7)
					(thickness 0.15)
				)
				(justify left bottom mirror)
			)
		)
		(fp_text user "Author: Antmicro"
			(at -0.939 -3.399 90)
			(layer "B.Fab")
			(hide yes)
			(effects
				(font
					(size 0.7 0.7)
					(thickness 0.15)
				)
				(justify left bottom mirror)
			)
		)
		(fp_text user "License: Apache-2.0"
			(at -0.939 -5.799 90)
			(layer "B.Fab")
			(hide yes)
			(effects
				(font
					(size 0.7 0.7)
					(thickness 0.15)
				)
				(justify left bottom mirror)
			)
		)
		(pad "1" smd roundrect
			(at -0.48 0 270)
			(size 0.59 0.64)
			(layers "B.Cu" "B.Paste" "B.Mask")
			(roundrect_rratio 0.25)
			(net 1 "GND")
			(pintype "passive")
		)
		(pad "2" smd roundrect
			(at 0.48 0 270)
			(size 0.59 0.64)
			(layers "B.Cu" "B.Paste" "B.Mask")
			(roundrect_rratio 0.25)
			(net 133 "/USB Debug, DP/PDC_LDO_1V8")
			(pintype "passive")
		)
	)
	(footprint "antmicro-footprints:R_0402_1005Metric"
		(layer "B.Cu")
		(at 90.39 104.31 45)
		(descr "Resistor SMD 0402")
		(tags "resistor SMD 0402")
		(property "Reference" "R224"
			(at 2.135462 1.414214 -135)
			(layer "B.SilkS")
			(effects
				(font
					(size 0.7 0.7)
					(thickness 0.15)
				)
				(justify left bottom mirror)
			)
		)
		(property "Value" "R_499R_0402"
			(at -1.011843 -1.772046 -135)
			(layer "B.Fab")
			(effects
				(font
					(size 0.7 0.7)
					(thickness 0.15)
				)
				(justify left bottom mirror)
			)
		)
		(property "Footprint" "antmicro-footprints:R_0402_1005Metric"
			(at 0 0 45)
			(layer "F.Fab")
			(hide yes)
			(effects
				(font
					(size 1.27 1.27)
					(thickness 0.15)
				)
			)
		)
		(property "Datasheet" "https://www.mouser.com/datasheet/2/54/cr-1858361.pdf"
			(at 0 0 45)
			(layer "F.Fab")
			(hide yes)
			(effects
				(font
					(size 1.27 1.27)
					(thickness 0.15)
				)
			)
		)
		(property "Author" "Antmicro"
			(at 100.232926 -33.363691 0)
			(layer "B.Fab")
			(hide yes)
			(effects
				(font
					(size 1 1)
					(thickness 0.15)
				)
				(justify mirror)
			)
		)
		(property "License" "Apache-2.0"
			(at 100.232926 -33.363691 0)
			(layer "B.Fab")
			(hide yes)
			(effects
				(font
					(size 1 1)
					(thickness 0.15)
				)
				(justify mirror)
			)
		)
		(property "MPN" "CR0402-FX-4990GLF"
			(at 100.232926 -33.363691 0)
			(layer "B.Fab")
			(hide yes)
			(effects
				(font
					(size 1 1)
					(thickness 0.15)
				)
				(justify mirror)
			)
		)
		(property "Manufacturer" "Bourns"
			(at 100.232926 -33.363691 0)
			(layer "B.Fab")
			(hide yes)
			(effects
				(font
					(size 1 1)
					(thickness 0.15)
				)
				(justify mirror)
			)
		)
		(property "Tolerance" "1%"
			(at 100.232926 -33.363691 0)
			(layer "B.Fab")
			(hide yes)
			(effects
				(font
					(size 1 1)
					(thickness 0.15)
				)
				(justify mirror)
			)
		)
		(property "Val" "499R"
			(at 100.232926 -33.363691 0)
			(layer "B.Fab")
			(hide yes)
			(effects
				(font
					(size 1 1)
					(thickness 0.15)
				)
				(justify mirror)
			)
		)
		(sheetname "HDMI")
		(sheetfile "hdmi.kicad_sch")
		(attr smd)
		(fp_poly
			(pts
				(xy -0.925 0.47) (xy 0.925 0.47) (xy 0.925 -0.47) (xy -0.925 -0.47)
			)
			(stroke
				(width 0.05)
				(type default)
			)
			(fill none)
			(layer "B.CrtYd")
		)
		(fp_poly
			(pts
				(xy -0.5 0.25) (xy 0.5 0.25) (xy 0.5 -0.25) (xy -0.5 -0.25)
			)
			(stroke
				(width 0.15)
				(type solid)
			)
			(fill none)
			(layer "B.Fab")
		)
		(fp_text user "${REFERENCE}"
			(at -0.95 -3.168 -135)
			(layer "B.Fab")
			(hide yes)
			(effects
				(font
					(size 0.7 0.7)
					(thickness 0.15)
				)
				(justify left bottom mirror)
			)
		)
		(fp_text user "License: Apache-2.0"
			(at -0.949999 -5.169 -135)
			(layer "B.Fab")
			(hide yes)
			(effects
				(font
					(size 0.7 0.7)
					(thickness 0.15)
				)
				(justify left bottom mirror)
			)
		)
		(fp_text user "Author: Antmicro"
			(at -0.95 -4.169 -135)
			(layer "B.Fab")
			(hide yes)
			(effects
				(font
					(size 0.7 0.7)
					(thickness 0.15)
				)
				(justify left bottom mirror)
			)
		)
		(pad "1" smd roundrect
			(at -0.48 0 45)
			(size 0.59 0.64)
			(layers "B.Cu" "B.Paste" "B.Mask")
			(roundrect_rratio 0.25)
			(net 623 "Net-(Q2-D)")
			(pintype "passive")
		)
		(pad "2" smd roundrect
			(at 0.48 0 45)
			(size 0.59 0.64)
			(layers "B.Cu" "B.Paste" "B.Mask")
			(roundrect_rratio 0.25)
			(net 495 "/HDMI/HDMI_CLK_P")
			(pintype "passive")
		)
	)
	(footprint "antmicro-footprints:R_0402_1005Metric"
		(layer "B.Cu")
		(at 75.23 116 90)
		(descr "Resistor SMD 0402")
		(tags "resistor SMD 0402")
		(property "Reference" "R109"
			(at 1.4 1.27 -90)
			(layer "B.SilkS")
			(effects
				(font
					(size 0.7 0.7)
					(thickness 0.15)
				)
				(justify left bottom mirror)
			)
		)
		(property "Value" "R_2M_0402"
			(at 0 -1.4 -90)
			(layer "B.Fab")
			(effects
				(font
					(size 0.7 0.7)
					(thickness 0.15)
				)
				(justify left bottom mirror)
			)
		)
		(property "Footprint" "antmicro-footprints:R_0402_1005Metric"
			(at 0 0 90)
			(layer "F.Fab")
			(hide yes)
			(effects
				(font
					(size 1.27 1.27)
					(thickness 0.15)
				)
			)
		)
		(property "Datasheet" "https://www.mouser.com/datasheet/2/447/YAGEO_PYu_RC_Group_51_RoHS_L_12-3313492.pdf"
			(at 0 0 90)
			(layer "F.Fab")
			(hide yes)
			(effects
				(font
					(size 1.27 1.27)
					(thickness 0.15)
				)
			)
		)
		(property "Description" "SMD Chip Resistor, 2 Mohm, ± 1%, 62.5 mW, 0402 [1005 Metric], Thick Film, General Purpose"
			(at 0 0 90)
			(layer "F.Fab")
			(hide yes)
			(effects
				(font
					(size 1.27 1.27)
					(thickness 0.15)
				)
			)
		)
		(property "Author" "Antmicro"
			(at 191.23 40.77 0)
			(layer "B.Fab")
			(hide yes)
			(effects
				(font
					(size 1 1)
					(thickness 0.15)
				)
				(justify mirror)
			)
		)
		(property "License" "Apache-2.0"
			(at 191.23 40.77 0)
			(layer "B.Fab")
			(hide yes)
			(effects
				(font
					(size 1 1)
					(thickness 0.15)
				)
				(justify mirror)
			)
		)
		(property "MPN" "RC0402FR-072ML"
			(at 191.23 40.77 0)
			(layer "B.Fab")
			(hide yes)
			(effects
				(font
					(size 1 1)
					(thickness 0.15)
				)
				(justify mirror)
			)
		)
		(property "Manufacturer" "YAGEO"
			(at 191.23 40.77 0)
			(layer "B.Fab")
			(hide yes)
			(effects
				(font
					(size 1 1)
					(thickness 0.15)
				)
				(justify mirror)
			)
		)
		(property "Tolerance" "1%"
			(at 191.23 40.77 0)
			(layer "B.Fab")
			(hide yes)
			(effects
				(font
					(size 1 1)
					(thickness 0.15)
				)
				(justify mirror)
			)
		)
		(property "Val" "2M"
			(at 191.23 40.77 0)
			(layer "B.Fab")
			(hide yes)
			(effects
				(font
					(size 1 1)
					(thickness 0.15)
				)
				(justify mirror)
			)
		)
		(sheetname "USB Debug, DP")
		(sheetfile "usb.kicad_sch")
		(attr smd)
		(fp_rect
			(start -0.925 0.47)
			(end 0.925 -0.47)
			(stroke
				(width 0.05)
				(type default)
			)
			(fill none)
			(layer "B.CrtYd")
		)
		(fp_rect
			(start -0.5 0.25)
			(end 0.5 -0.25)
			(stroke
				(width 0.15)
				(type solid)
			)
			(fill none)
			(layer "B.Fab")
		)
		(fp_text user "${REFERENCE}"
			(at -0.95 -3.168 -90)
			(layer "B.Fab")
			(hide yes)
			(effects
				(font
					(size 0.7 0.7)
					(thickness 0.15)
				)
				(justify left bottom mirror)
			)
		)
		(fp_text user "License: Apache-2.0"
			(at -0.95 -5.169 -90)
			(layer "B.Fab")
			(hide yes)
			(effects
				(font
					(size 0.7 0.7)
					(thickness 0.15)
				)
				(justify left bottom mirror)
			)
		)
		(fp_text user "Author: Antmicro"
			(at -0.95 -4.169 -90)
			(layer "B.Fab")
			(hide yes)
			(effects
				(font
					(size 0.7 0.7)
					(thickness 0.15)
				)
				(justify left bottom mirror)
			)
		)
		(pad "1" smd roundrect
			(at -0.48 0 90)
			(size 0.59 0.64)
			(layers "B.Cu" "B.Paste" "B.Mask")
			(roundrect_rratio 0.25)
			(net 615 "/USB Debug, DP/USBC0_SBU_N")
			(pintype "passive")
		)
		(pad "2" smd roundrect
			(at 0.48 0 90)
			(size 0.59 0.64)
			(layers "B.Cu" "B.Paste" "B.Mask")
			(roundrect_rratio 0.25)
			(net 1 "GND")
			(pintype "passive")
		)
	)
)
